# S9S_MB_2U (Grand Teton) — schematic netlist excerpt (pin names and nets, part order shuffled) for the footprints in the layout excerpt that follows; sources: Cadence DE-HDL packaged netlist, KiCad conversion of 03242023_DA0F0TMBIJ0_F0T_Motherboard_J_brd_V01_OCP.brd

R1309  Q_RES  33.2 1% CHIP  pkg 0402LF  page 205 : A = IRQ_SMI_ACTIVE_N ; B = IRQ_SMI_ACTIVE_BMC_N
PR4220  Q_RES  0 5% CHIP  pkg 0402LF  page 274 : A = PVCCINFAON_CPU0_CSPIN ; B = GND

(kicad_pcb
	(version 20260206)
	(generator "pcbnew")
	(generator_version "10.0")
	(general
		(thickness 1.6)
		(legacy_teardrops no)
	)
	(paper "A4")
	(title_block
		(title "03242023_DA0F0TMBIJ0_F0T_Motherboard_J_brd_V01_OCP.brd")
		(comment 1 "Grand Teton / footprints 5416-5417 of 6105")
	)
	(layers
		(0 "F.Cu" signal "TOP")
		(4 "In1.Cu" signal "GND")
		(6 "In2.Cu" signal "IN1")
		(8 "In3.Cu" signal "GND1")
		(10 "In4.Cu" signal "IN2")
		(12 "In5.Cu" signal "GND2")
		(14 "In6.Cu" signal "IN3")
		(16 "In7.Cu" signal "GND3")
		(18 "In8.Cu" signal "VCC")
		(20 "In9.Cu" signal "VCC1")
		(22 "In10.Cu" signal "GND4")
		(24 "In11.Cu" signal "IN4")
		(26 "In12.Cu" signal "GND5")
		(28 "In13.Cu" signal "IN5")
		(30 "In14.Cu" signal "GND6")
		(32 "In15.Cu" signal "IN6")
		(34 "In16.Cu" signal "GND7")
		(2 "B.Cu" signal "BOTTOM")
		(9 "F.Adhes" user "F.Adhesive")
		(11 "B.Adhes" user "B.Adhesive")
		(13 "F.Paste" user "Package Geometry/Pastemask Top")
		(15 "B.Paste" user "Package Geometry/Pastemask Bottom")
		(5 "F.SilkS" user "Ref Des/Silkscreen Top")
		(7 "B.SilkS" user "Ref Des/Silkscreen Bottom")
		(1 "F.Mask" user "Board Geometry/Soldermask Top")
		(3 "B.Mask" user "Board Geometry/Soldermask Bottom")
		(17 "Dwgs.User" user "User.Drawings")
		(19 "Cmts.User" user "User.Comments")
		(21 "Eco1.User" user "User.Eco1")
		(23 "Eco2.User" user "User.Eco2")
		(25 "Edge.Cuts" user "Board Geometry/Outline")
		(27 "Margin" user)
		(31 "F.CrtYd" user "Package Geometry/Place Bound Top")
		(29 "B.CrtYd" user "Package Geometry/Place Bound Bottom")
		(35 "F.Fab" user "Ref Des/Assembly Top")
		(33 "B.Fab" user "Ref Des/Assembly Bottom")
	)
	(footprint ""
		(layer "B.Cu")
		(at 343.050368 -30.636972)
		(property "Reference" "R1309"
			(at 0 0 0)
			(layer "B.SilkS")
			(hide yes)
			(effects
				(font
					(size 1.27 1.27)
				)
				(justify mirror)
			)
		)
		(property "Value" ""
			(at 0 0 0)
			(layer "B.Fab")
			(effects
				(font
					(size 1.27 1.27)
				)
				(justify mirror)
			)
		)
		(duplicate_pad_numbers_are_jumpers no)
		(fp_line
			(start -0.7874 -0.4064)
			(end -0.7874 0.4064)
			(stroke
				(width 0.1524)
				(type default)
			)
			(layer "B.SilkS")
		)
		(fp_line
			(start -0.7874 0.4064)
			(end 0.7874 0.4064)
			(stroke
				(width 0.1524)
				(type default)
			)
			(layer "B.SilkS")
		)
		(fp_line
			(start 0.7874 -0.4064)
			(end -0.7874 -0.4064)
			(stroke
				(width 0.1524)
				(type default)
			)
			(layer "B.SilkS")
		)
		(fp_line
			(start 0.7874 0.4064)
			(end 0.7874 -0.4064)
			(stroke
				(width 0.1524)
				(type default)
			)
			(layer "B.SilkS")
		)
		(fp_line
			(start -0.67945 -0.3048)
			(end -0.67945 0.3048)
			(stroke
				(width 0.1)
				(type default)
			)
			(layer "B.Fab")
		)
		(fp_line
			(start -0.67945 0.3048)
			(end -0.120396 0.3048)
			(stroke
				(width 0.1)
				(type default)
			)
			(layer "B.Fab")
		)
		(fp_line
			(start -0.12065 -0.3048)
			(end -0.67945 -0.3048)
			(stroke
				(width 0.1)
				(type default)
			)
			(layer "B.Fab")
		)
		(fp_line
			(start -0.12065 -0.2794)
			(end -0.12065 -0.3048)
			(stroke
				(width 0.1)
				(type default)
			)
			(layer "B.Fab")
		)
		(fp_line
			(start -0.120396 0.2794)
			(end 0.12065 0.2794)
			(stroke
				(width 0.1)
				(type default)
			)
			(layer "B.Fab")
		)
		(fp_line
			(start -0.120396 0.3048)
			(end -0.120396 0.2794)
			(stroke
				(width 0.1)
				(type default)
			)
			(layer "B.Fab")
		)
		(fp_line
			(start 0.12065 -0.305054)
			(end 0.12065 -0.2794)
			(stroke
				(width 0.1)
				(type default)
			)
			(layer "B.Fab")
		)
		(fp_line
			(start 0.12065 -0.2794)
			(end -0.12065 -0.2794)
			(stroke
				(width 0.1)
				(type default)
			)
			(layer "B.Fab")
		)
		(fp_line
			(start 0.12065 0.2794)
			(end 0.12065 0.3048)
			(stroke
				(width 0.1)
				(type default)
			)
			(layer "B.Fab")
		)
		(fp_line
			(start 0.12065 0.3048)
			(end 0.67945 0.3048)
			(stroke
				(width 0.1)
				(type default)
			)
			(layer "B.Fab")
		)
		(fp_line
			(start 0.67945 -0.305054)
			(end 0.12065 -0.305054)
			(stroke
				(width 0.1)
				(type default)
			)
			(layer "B.Fab")
		)
		(fp_line
			(start 0.67945 0.3048)
			(end 0.67945 -0.305054)
			(stroke
				(width 0.1)
				(type default)
			)
			(layer "B.Fab")
		)
		(pad "1" smd circle
			(at 0.40005 0 180)
			(size 0 0)
			(layers "B.Cu" "B.Mask" "B.Paste")
			(net "IRQ_SMI_ACTIVE_N")
		)
		(pad "2" smd circle
			(at -0.40005 0 180)
			(size 0 0)
			(layers "B.Cu" "B.Mask" "B.Paste")
			(net "IRQ_SMI_ACTIVE_BMC_N")
		)
	)
	(footprint ""
		(layer "B.Cu")
		(at 423.683938 -135.769096 180)
		(property "Reference" "PR4220"
			(at 0 0 0)
			(layer "B.SilkS")
			(hide yes)
			(effects
				(font
					(size 1.27 1.27)
				)
				(justify mirror)
			)
		)
		(property "Value" ""
			(at 0 0 0)
			(layer "B.Fab")
			(effects
				(font
					(size 1.27 1.27)
				)
				(justify mirror)
			)
		)
		(duplicate_pad_numbers_are_jumpers no)
		(fp_line
			(start 0.7874 0.4064)
			(end 0.7874 -0.4064)
			(stroke
				(width 0.1524)
				(type default)
			)
			(layer "B.SilkS")
		)
		(fp_line
			(start 0.7874 -0.4064)
			(end -0.7874 -0.4064)
			(stroke
				(width 0.1524)
				(type default)
			)
			(layer "B.SilkS")
		)
		(fp_line
			(start -0.7874 0.4064)
			(end 0.7874 0.4064)
			(stroke
				(width 0.1524)
				(type default)
			)
			(layer "B.SilkS")
		)
		(fp_line
			(start -0.7874 -0.4064)
			(end -0.7874 0.4064)
			(stroke
				(width 0.1524)
				(type default)
			)
			(layer "B.SilkS")
		)
		(fp_line
			(start 0.67945 0.3048)
			(end 0.67945 -0.305054)
			(stroke
				(width 0.1)
				(type default)
			)
			(layer "B.Fab")
		)
		(fp_line
			(start 0.67945 -0.305054)
			(end 0.12065 -0.305054)
			(stroke
				(width 0.1)
				(type default)
			)
			(layer "B.Fab")
		)
		(fp_line
			(start 0.12065 0.3048)
			(end 0.67945 0.3048)
			(stroke
				(width 0.1)
				(type default)
			)
			(layer "B.Fab")
		)
		(fp_line
			(start 0.12065 0.2794)
			(end 0.12065 0.3048)
			(stroke
				(width 0.1)
				(type default)
			)
			(layer "B.Fab")
		)
		(fp_line
			(start 0.12065 -0.2794)
			(end -0.12065 -0.2794)
			(stroke
				(width 0.1)
				(type default)
			)
			(layer "B.Fab")
		)
		(fp_line
			(start 0.12065 -0.305054)
			(end 0.12065 -0.2794)
			(stroke
				(width 0.1)
				(type default)
			)
			(layer "B.Fab")
		)
		(fp_line
			(start -0.120396 0.3048)
			(end -0.120396 0.2794)
			(stroke
				(width 0.1)
				(type default)
			)
			(layer "B.Fab")
		)
		(fp_line
			(start -0.120396 0.2794)
			(end 0.12065 0.2794)
			(stroke
				(width 0.1)
				(type default)
			)
			(layer "B.Fab")
		)
		(fp_line
			(start -0.12065 -0.2794)
			(end -0.12065 -0.3048)
			(stroke
				(width 0.1)
				(type default)
			)
			(layer "B.Fab")
		)
		(fp_line
			(start -0.12065 -0.3048)
			(end -0.67945 -0.3048)
			(stroke
				(width 0.1)
				(type default)
			)
			(layer "B.Fab")
		)
		(fp_line
			(start -0.67945 0.3048)
			(end -0.120396 0.3048)
			(stroke
				(width 0.1)
				(type default)
			)
			(layer "B.Fab")
		)
		(fp_line
			(start -0.67945 -0.3048)
			(end -0.67945 0.3048)
			(stroke
				(width 0.1)
				(type default)
			)
			(layer "B.Fab")
		)
		(pad "1" smd circle
			(at 0.40005 0)
			(size 0 0)
			(layers "B.Cu" "B.Mask" "B.Paste")
			(net "PVCCINFAON_CPU0_CSPIN")
		)
		(pad "2" smd circle
			(at -0.40005 0)
			(size 0 0)
			(layers "B.Cu" "B.Mask" "B.Paste")
			(net "GND")
		)
	)
)
